(kicad_pcb
	(version 20260206)
	(generator "pcbnew")
	(generator_version "10.0")
	(general
		(thickness 1.6)
		(legacy_teardrops no)
	)
	(paper "A4")
	(title_block
		(title "Bryce Canyon_IOM_M2_16342-2_OCP.brd")
		(comment 1 "Bryce Canyon / footprint 752 of 1146 (U32), pads 1-14 of 14")
	)
	(layers
		(0 "F.Cu" signal "TOP")
		(4 "In1.Cu" signal "L2GND")
		(6 "In2.Cu" signal "L3")
		(8 "In3.Cu" signal "L4VCC")
		(10 "In4.Cu" signal "L5VCC")
		(12 "In5.Cu" signal "L6")
		(14 "In6.Cu" signal "L7GND")
		(2 "B.Cu" signal "BOTTOM")
		(9 "F.Adhes" user "F.Adhesive")
		(11 "B.Adhes" user "B.Adhesive")
		(13 "F.Paste" user "Package Geometry/Pastemask Top")
		(15 "B.Paste" user "Package Geometry/Pastemask Bottom")
		(5 "F.SilkS" user "Ref Des/Silkscreen Top")
		(7 "B.SilkS" user "Ref Des/Silkscreen Bottom")
		(1 "F.Mask" user "Board Geometry/Soldermask Top")
		(3 "B.Mask" user "Board Geometry/Soldermask Bottom")
		(17 "Dwgs.User" user "User.Drawings")
		(19 "Cmts.User" user "User.Comments")
		(21 "Eco1.User" user "User.Eco1")
		(23 "Eco2.User" user "User.Eco2")
		(25 "Edge.Cuts" user "Board Geometry/Outline")
		(27 "Margin" user)
		(31 "F.CrtYd" user "Package Geometry/Place Bound Top")
		(29 "B.CrtYd" user "Package Geometry/Place Bound Bottom")
		(35 "F.Fab" user "Ref Des/Assembly Top")
		(33 "B.Fab" user "Ref Des/Assembly Bottom")
	)
	(footprint ""
		(layer "B.Cu")
		(at 84.871306 -170.019726 90)
		(property "Reference" "U32"
			(at 0 0 90)
			(layer "B.SilkS")
			(hide yes)
			(effects
				(font
					(size 1.27 1.27)
				)
				(justify mirror)
			)
		)
		(property "Value" "SN74LVC126APWR-1-GP"
			(at 0 -10.6172 90)
			(unlocked yes)
			(layer "B.Fab")
			(hide yes)
			(effects
				(font
					(size 1.016 1.016)
					(thickness 0.1524)
				)
				(justify mirror)
			)
		)
		(property "Device Type" "SSOIC14-1H48"
			(at 0 -12.1412 90)
			(unlocked yes)
			(layer "B.Fab")
			(hide yes)
			(effects
				(font
					(size 1.016 1.016)
					(thickness 0.1524)
				)
				(justify mirror)
			)
		)
		(duplicate_pad_numbers_are_jumpers no)
		(pad "1" smd rect
			(at 1.95072 2.8194 270)
			(size 0.3556 1.524)
			(layers "B.Cu" "B.Mask" "B.Paste")
			(net "PCIE_RST_R_N")
		)
		(pad "2" smd rect
			(at 1.30048 2.8194 270)
			(size 0.3556 1.524)
			(layers "B.Cu" "B.Mask" "B.Paste")
			(net "UART_COMP_R_TX")
		)
		(pad "3" smd rect
			(at 0.65024 2.8194 270)
			(size 0.3556 1.524)
			(layers "B.Cu" "B.Mask" "B.Paste")
			(net "UART_COMP_OUT_TX")
		)
		(pad "4" smd rect
			(at 0 2.8194 270)
			(size 0.3556 1.524)
			(layers "B.Cu" "B.Mask" "B.Paste")
			(net "PCIE_RST_R_N")
		)
		(pad "5" smd rect
			(at -0.65024 2.8194 270)
			(size 0.3556 1.524)
			(layers "B.Cu" "B.Mask" "B.Paste")
			(net "UART_COMP_IN_RX_AND_R")
		)
		(pad "6" smd rect
			(at -1.30048 2.8194 270)
			(size 0.3556 1.524)
			(layers "B.Cu" "B.Mask" "B.Paste")
			(net "UART_COMP_R_RX")
		)
		(pad "7" smd rect
			(at -1.95072 2.8194 270)
			(size 0.3556 1.524)
			(layers "B.Cu" "B.Mask" "B.Paste")
			(net "GND")
		)
		(pad "8" smd rect
			(at -1.95072 -2.8194 270)
			(size 0.3556 1.524)
			(layers "B.Cu" "B.Mask" "B.Paste")
			(net "UART_EXP_BMC_TX")
		)
		(pad "9" smd rect
			(at -1.30048 -2.8194 270)
			(size 0.3556 1.524)
			(layers "B.Cu" "B.Mask" "B.Paste")
			(net "UART_SDB_TX_R")
		)
		(pad "10" smd rect
			(at -0.65024 -2.8194 270)
			(size 0.3556 1.524)
			(layers "B.Cu" "B.Mask" "B.Paste")
			(net "EXP_UART_EN_R")
		)
		(pad "11" smd rect
			(at 0 -2.8194 270)
			(size 0.3556 1.524)
			(layers "B.Cu" "B.Mask" "B.Paste")
			(net "UART_SDB_RX")
		)
		(pad "12" smd rect
			(at 0.65024 -2.8194 270)
			(size 0.3556 1.524)
			(layers "B.Cu" "B.Mask" "B.Paste")
			(net "UART_EXP_BMC_RX")
		)
		(pad "13" smd rect
			(at 1.30048 -2.8194 270)
			(size 0.3556 1.524)
			(layers "B.Cu" "B.Mask" "B.Paste")
			(net "EXP_UART_EN_R")
		)
		(pad "14" smd rect
			(at 1.95072 -2.8194 270)
			(size 0.3556 1.524)
			(layers "B.Cu" "B.Mask" "B.Paste")
			(net "P3V3_STBY")
		)
	)
)
